(kicad_pcb
	(version 20260206)
	(generator "pcbnew")
	(generator_version "10.0")
	(general
		(thickness 1.6)
		(legacy_teardrops no)
	)
	(paper "A4")
	(title_block
		(title "04192023_DAF0TMB3IC0_F0TG_MB_C_brd_V02_OCP.brd")
		(comment 1 "Grand Teton / footprint 3955 of 8354 (U25), pads 541-651 of 6102")
	)
	(layers
		(0 "F.Cu" signal "TOP")
		(4 "In1.Cu" signal "GND")
		(6 "In2.Cu" signal "IN1")
		(8 "In3.Cu" signal "GND1")
		(10 "In4.Cu" signal "IN2")
		(12 "In5.Cu" signal "GND2")
		(14 "In6.Cu" signal "IN3")
		(16 "In7.Cu" signal "GND3")
		(18 "In8.Cu" signal "VCC")
		(20 "In9.Cu" signal "VCC1")
		(22 "In10.Cu" signal "GND4")
		(24 "In11.Cu" signal "IN4")
		(26 "In12.Cu" signal "GND5")
		(28 "In13.Cu" signal "IN5")
		(30 "In14.Cu" signal "GND6")
		(32 "In15.Cu" signal "IN6")
		(34 "In16.Cu" signal "GND7")
		(2 "B.Cu" signal "BOTTOM")
		(9 "F.Adhes" user "F.Adhesive")
		(11 "B.Adhes" user "B.Adhesive")
		(13 "F.Paste" user "Package Geometry/Pastemask Top")
		(15 "B.Paste" user "Package Geometry/Pastemask Bottom")
		(5 "F.SilkS" user "Ref Des/Silkscreen Top")
		(7 "B.SilkS" user "Ref Des/Silkscreen Bottom")
		(1 "F.Mask" user "Board Geometry/Soldermask Top")
		(3 "B.Mask" user "Board Geometry/Soldermask Bottom")
		(17 "Dwgs.User" user "User.Drawings")
		(19 "Cmts.User" user "User.Comments")
		(21 "Eco1.User" user "User.Eco1")
		(23 "Eco2.User" user "User.Eco2")
		(25 "Edge.Cuts" user "Board Geometry/Outline")
		(27 "Margin" user)
		(31 "F.CrtYd" user "Package Geometry/Place Bound Top")
		(29 "B.CrtYd" user "Package Geometry/Place Bound Bottom")
		(35 "F.Fab" user "Ref Des/Assembly Top")
		(33 "B.Fab" user "Ref Des/Assembly Bottom")
	)
	(footprint ""
		(layer "F.Cu")
		(at 359.867962 -258.880102 180)
		(property "Reference" "U25"
			(at -45.78477 -62.086744 0)
			(unlocked yes)
			(layer "F.SilkS")
			(effects
				(font
					(size 0.7874 0.5842)
					(thickness 0.1524)
				)
			)
		)
		(property "Value" ""
			(at 0 0 180)
			(layer "F.Fab")
			(effects
				(font
					(size 1.27 1.27)
				)
			)
		)
		(duplicate_pad_numbers_are_jumpers no)
		(pad "AG50" smd circle
			(at 10.9601 -15.750032 180)
			(size 0.450088 0.450088)
			(layers "F.Cu" "F.Mask" "F.Paste")
			(net "GMI_CPU0_G0_CPU1_G2_TX_DN<10>")
		)
		(pad "AG51" smd circle
			(at 11.8999 -15.750032 180)
			(size 0.450088 0.450088)
			(layers "F.Cu" "F.Mask" "F.Paste")
			(net "GND")
		)
		(pad "AG52" smd circle
			(at 12.839954 -15.750032 180)
			(size 0.450088 0.450088)
			(layers "F.Cu" "F.Mask" "F.Paste")
			(net "GMI_CPU0_G0_CPU1_G2_TX_DP<13>")
		)
		(pad "AG53" smd circle
			(at 13.780008 -15.750032 180)
			(size 0.450088 0.450088)
			(layers "F.Cu" "F.Mask" "F.Paste")
			(net "GMI_CPU0_G0_CPU1_G2_TX_DN<13>")
		)
		(pad "AG54" smd circle
			(at 14.720062 -15.750032 180)
			(size 0.450088 0.450088)
			(layers "F.Cu" "F.Mask" "F.Paste")
			(net "GND")
		)
		(pad "AG55" smd circle
			(at 15.660116 -15.750032 180)
			(size 0.450088 0.450088)
			(layers "F.Cu" "F.Mask" "F.Paste")
			(net "M_C_CPU0_SA_DQS_DP<8>")
		)
		(pad "AG56" smd circle
			(at 16.599916 -15.750032 180)
			(size 0.450088 0.450088)
			(layers "F.Cu" "F.Mask" "F.Paste")
			(net "GND")
		)
		(pad "AG57" smd circle
			(at 17.53997 -15.750032 180)
			(size 0.450088 0.450088)
			(layers "F.Cu" "F.Mask" "F.Paste")
			(net "M_C_CPU0_SA_DQ<28>")
		)
		(pad "AG58" smd circle
			(at 18.480024 -15.750032 180)
			(size 0.450088 0.450088)
			(layers "F.Cu" "F.Mask" "F.Paste")
			(net "GND")
		)
		(pad "AG59" smd circle
			(at 19.420078 -15.750032 180)
			(size 0.450088 0.450088)
			(layers "F.Cu" "F.Mask" "F.Paste")
			(net "M_D_CPU0_SA_DQS_DP<8>")
		)
		(pad "AG60" smd circle
			(at 20.359878 -15.750032 180)
			(size 0.450088 0.450088)
			(layers "F.Cu" "F.Mask" "F.Paste")
			(net "M_D_CPU0_SA_DQ<28>")
		)
		(pad "AG61" smd circle
			(at 21.299932 -15.750032 180)
			(size 0.450088 0.450088)
			(layers "F.Cu" "F.Mask" "F.Paste")
			(net "GND")
		)
		(pad "AG62" smd circle
			(at 22.239986 -15.750032 180)
			(size 0.450088 0.450088)
			(layers "F.Cu" "F.Mask" "F.Paste")
			(net "M_B_CPU0_SA_DQS_DP<8>")
		)
		(pad "AG63" smd circle
			(at 23.18004 -15.750032 180)
			(size 0.450088 0.450088)
			(layers "F.Cu" "F.Mask" "F.Paste")
			(net "GND")
		)
		(pad "AG64" smd circle
			(at 24.120094 -15.750032 180)
			(size 0.450088 0.450088)
			(layers "F.Cu" "F.Mask" "F.Paste")
			(net "M_B_CPU0_SA_DQ<28>")
		)
		(pad "AG65" smd circle
			(at 25.059894 -15.750032 180)
			(size 0.450088 0.450088)
			(layers "F.Cu" "F.Mask" "F.Paste")
			(net "GND")
		)
		(pad "AG66" smd circle
			(at 25.999948 -15.750032 180)
			(size 0.450088 0.450088)
			(layers "F.Cu" "F.Mask" "F.Paste")
			(net "M_F_CPU0_SA_DQS_DP<8>")
		)
		(pad "AG67" smd circle
			(at 26.940002 -15.750032 180)
			(size 0.450088 0.450088)
			(layers "F.Cu" "F.Mask" "F.Paste")
			(net "M_F_CPU0_SA_DQ<28>")
		)
		(pad "AG68" smd circle
			(at 27.880056 -15.750032 180)
			(size 0.450088 0.450088)
			(layers "F.Cu" "F.Mask" "F.Paste")
			(net "GND")
		)
		(pad "AG69" smd circle
			(at 28.82011 -15.750032 180)
			(size 0.450088 0.450088)
			(layers "F.Cu" "F.Mask" "F.Paste")
			(net "M_E_CPU0_SA_DQS_DP<8>")
		)
		(pad "AG70" smd circle
			(at 29.75991 -15.750032 180)
			(size 0.450088 0.450088)
			(layers "F.Cu" "F.Mask" "F.Paste")
			(net "GND")
		)
		(pad "AG71" smd circle
			(at 30.699964 -15.750032 180)
			(size 0.450088 0.450088)
			(layers "F.Cu" "F.Mask" "F.Paste")
			(net "M_E_CPU0_SA_DQ<28>")
		)
		(pad "AG72" smd circle
			(at 31.640018 -15.750032 180)
			(size 0.450088 0.450088)
			(layers "F.Cu" "F.Mask" "F.Paste")
			(net "GND")
		)
		(pad "AG73" smd circle
			(at 32.580072 -15.750032 180)
			(size 0.450088 0.450088)
			(layers "F.Cu" "F.Mask" "F.Paste")
			(net "M_A_CPU0_SA_DQS_DP<8>")
		)
		(pad "AG74" smd circle
			(at 33.519872 -15.750032 180)
			(size 0.450088 0.450088)
			(layers "F.Cu" "F.Mask" "F.Paste")
			(net "M_A_CPU0_SA_DQ<28>")
		)
		(pad "AG75" smd circle
			(at 34.459926 -15.750032 180)
			(size 0.450088 0.450088)
			(layers "F.Cu" "F.Mask" "F.Paste")
			(net "GND")
		)
		(pad "AH2" smd circle
			(at -33.690052 -14.940026 180)
			(size 0.450088 0.450088)
			(layers "F.Cu" "F.Mask" "F.Paste")
			(net "M_G_CPU0_SA_DQ<30>")
		)
		(pad "AH3" smd circle
			(at -32.749998 -14.940026 180)
			(size 0.450088 0.450088)
			(layers "F.Cu" "F.Mask" "F.Paste")
			(net "GND")
		)
		(pad "AH4" smd circle
			(at -31.809944 -14.940026 180)
			(size 0.450088 0.450088)
			(layers "F.Cu" "F.Mask" "F.Paste")
			(net "M_G_CPU0_SA_DQ<29>")
		)
		(pad "AH5" smd circle
			(at -30.86989 -14.940026 180)
			(size 0.450088 0.450088)
			(layers "F.Cu" "F.Mask" "F.Paste")
			(net "GND")
		)
		(pad "AH6" smd circle
			(at -29.93009 -14.940026 180)
			(size 0.450088 0.450088)
			(layers "F.Cu" "F.Mask" "F.Paste")
			(net "M_K_CPU0_SA_DQ<30>")
		)
		(pad "AH7" smd circle
			(at -28.990036 -14.940026 180)
			(size 0.450088 0.450088)
			(layers "F.Cu" "F.Mask" "F.Paste")
			(net "M_K_CPU0_SA_DQ<29>")
		)
		(pad "AH8" smd circle
			(at -28.049982 -14.940026 180)
			(size 0.450088 0.450088)
			(layers "F.Cu" "F.Mask" "F.Paste")
			(net "GND")
		)
		(pad "AH9" smd circle
			(at -27.109928 -14.940026 180)
			(size 0.450088 0.450088)
			(layers "F.Cu" "F.Mask" "F.Paste")
			(net "M_L_CPU0_SA_DQ<30>")
		)
		(pad "AH10" smd circle
			(at -26.170128 -14.940026 180)
			(size 0.450088 0.450088)
			(layers "F.Cu" "F.Mask" "F.Paste")
			(net "GND")
		)
		(pad "AH11" smd circle
			(at -25.230074 -14.940026 180)
			(size 0.450088 0.450088)
			(layers "F.Cu" "F.Mask" "F.Paste")
			(net "M_L_CPU0_SA_DQ<29>")
		)
		(pad "AH12" smd circle
			(at -24.29002 -14.940026 180)
			(size 0.450088 0.450088)
			(layers "F.Cu" "F.Mask" "F.Paste")
			(net "GND")
		)
		(pad "AH13" smd circle
			(at -23.349966 -14.940026 180)
			(size 0.450088 0.450088)
			(layers "F.Cu" "F.Mask" "F.Paste")
			(net "M_H_CPU0_SA_DQ<30>")
		)
		(pad "AH14" smd circle
			(at -22.409912 -14.940026 180)
			(size 0.450088 0.450088)
			(layers "F.Cu" "F.Mask" "F.Paste")
			(net "M_H_CPU0_SA_DQ<29>")
		)
		(pad "AH15" smd circle
			(at -21.470112 -14.940026 180)
			(size 0.450088 0.450088)
			(layers "F.Cu" "F.Mask" "F.Paste")
			(net "GND")
		)
		(pad "AH16" smd circle
			(at -20.530058 -14.940026 180)
			(size 0.450088 0.450088)
			(layers "F.Cu" "F.Mask" "F.Paste")
			(net "M_J_CPU0_SA_DQ<30>")
		)
		(pad "AH17" smd circle
			(at -19.590004 -14.940026 180)
			(size 0.450088 0.450088)
			(layers "F.Cu" "F.Mask" "F.Paste")
			(net "GND")
		)
		(pad "AH18" smd circle
			(at -18.64995 -14.940026 180)
			(size 0.450088 0.450088)
			(layers "F.Cu" "F.Mask" "F.Paste")
			(net "M_J_CPU0_SA_DQ<29>")
		)
		(pad "AH19" smd circle
			(at -17.709896 -14.940026 180)
			(size 0.450088 0.450088)
			(layers "F.Cu" "F.Mask" "F.Paste")
			(net "GND")
		)
		(pad "AH20" smd circle
			(at -16.770096 -14.940026 180)
			(size 0.450088 0.450088)
			(layers "F.Cu" "F.Mask" "F.Paste")
			(net "M_I_CPU0_SA_DQ<30>")
		)
		(pad "AH21" smd circle
			(at -15.830042 -14.940026 180)
			(size 0.450088 0.450088)
			(layers "F.Cu" "F.Mask" "F.Paste")
			(net "M_I_CPU0_SA_DQ<29>")
		)
		(pad "AH22" smd circle
			(at -14.889988 -14.940026 180)
			(size 0.450088 0.450088)
			(layers "F.Cu" "F.Mask" "F.Paste")
			(net "PVDDCR_SOC_P0")
		)
		(pad "AH23" smd circle
			(at -13.949934 -14.940026 180)
			(size 0.450088 0.450088)
			(layers "F.Cu" "F.Mask" "F.Paste")
			(net "GND")
		)
		(pad "AH24" smd circle
			(at -13.00988 -14.940026 180)
			(size 0.450088 0.450088)
			(layers "F.Cu" "F.Mask" "F.Paste")
			(net "GND")
		)
		(pad "AH25" smd circle
			(at -12.07008 -14.940026 180)
			(size 0.450088 0.450088)
			(layers "F.Cu" "F.Mask" "F.Paste")
			(net "GND")
		)
		(pad "AH26" smd circle
			(at -11.130026 -14.940026 180)
			(size 0.450088 0.450088)
			(layers "F.Cu" "F.Mask" "F.Paste")
			(net "GND")
		)
		(pad "AH27" smd circle
			(at -10.189972 -14.940026 180)
			(size 0.450088 0.450088)
			(layers "F.Cu" "F.Mask" "F.Paste")
			(net "GND")
		)
		(pad "AH28" smd circle
			(at -9.249918 -14.940026 180)
			(size 0.450088 0.450088)
			(layers "F.Cu" "F.Mask" "F.Paste")
			(net "GND")
		)
		(pad "AH29" smd circle
			(at -8.310118 -14.940026 180)
			(size 0.450088 0.450088)
			(layers "F.Cu" "F.Mask" "F.Paste")
			(net "GND")
		)
		(pad "AH30" smd circle
			(at -7.370064 -14.940026 180)
			(size 0.450088 0.450088)
			(layers "F.Cu" "F.Mask" "F.Paste")
			(net "GND")
		)
		(pad "AH31" smd circle
			(at -6.43001 -14.940026 180)
			(size 0.450088 0.450088)
			(layers "F.Cu" "F.Mask" "F.Paste")
			(net "GND")
		)
		(pad "AH32" smd circle
			(at -5.489956 -14.940026 180)
			(size 0.450088 0.450088)
			(layers "F.Cu" "F.Mask" "F.Paste")
			(net "GND")
		)
		(pad "AH33" smd circle
			(at -4.549902 -14.940026 180)
			(size 0.450088 0.450088)
			(layers "F.Cu" "F.Mask" "F.Paste")
			(net "GND")
		)
		(pad "AH34" smd circle
			(at -3.610102 -14.940026 180)
			(size 0.450088 0.450088)
			(layers "F.Cu" "F.Mask" "F.Paste")
			(net "GND")
		)
		(pad "AH35" smd circle
			(at -2.670048 -14.940026 180)
			(size 0.450088 0.450088)
			(layers "F.Cu" "F.Mask" "F.Paste")
			(net "P5E_CPU0_G3_RX_DN<13>")
		)
		(pad "AH36" smd circle
			(at -1.729994 -14.940026 180)
			(size 0.450088 0.450088)
			(layers "F.Cu" "F.Mask" "F.Paste")
			(net "P5E_CPU0_G3_RX_DP<13>")
		)
		(pad "AH37" smd circle
			(at -0.78994 -14.940026 180)
			(size 0.450088 0.450088)
			(layers "F.Cu" "F.Mask" "F.Paste")
			(net "GND")
		)
		(pad "AH39" smd circle
			(at 1.089914 -14.940026 180)
			(size 0.450088 0.450088)
			(layers "F.Cu" "F.Mask" "F.Paste")
			(net "GND")
		)
		(pad "AH40" smd circle
			(at 2.029968 -14.940026 180)
			(size 0.450088 0.450088)
			(layers "F.Cu" "F.Mask" "F.Paste")
			(net "GMI_CPU0_G1_CPU1_G3_TX_DP<2>")
		)
		(pad "AH41" smd circle
			(at 2.970022 -14.940026 180)
			(size 0.450088 0.450088)
			(layers "F.Cu" "F.Mask" "F.Paste")
			(net "GMI_CPU0_G1_CPU1_G3_TX_DN<2>")
		)
		(pad "AH42" smd circle
			(at 3.910076 -14.940026 180)
			(size 0.450088 0.450088)
			(layers "F.Cu" "F.Mask" "F.Paste")
			(net "GND")
		)
		(pad "AH43" smd circle
			(at 4.849876 -14.940026 180)
			(size 0.450088 0.450088)
			(layers "F.Cu" "F.Mask" "F.Paste")
			(net "GND")
		)
		(pad "AH44" smd circle
			(at 5.78993 -14.940026 180)
			(size 0.450088 0.450088)
			(layers "F.Cu" "F.Mask" "F.Paste")
			(net "GND")
		)
		(pad "AH45" smd circle
			(at 6.729984 -14.940026 180)
			(size 0.450088 0.450088)
			(layers "F.Cu" "F.Mask" "F.Paste")
			(net "GND")
		)
		(pad "AH46" smd circle
			(at 7.670038 -14.940026 180)
			(size 0.450088 0.450088)
			(layers "F.Cu" "F.Mask" "F.Paste")
			(net "GND")
		)
		(pad "AH47" smd circle
			(at 8.610092 -14.940026 180)
			(size 0.450088 0.450088)
			(layers "F.Cu" "F.Mask" "F.Paste")
			(net "GND")
		)
		(pad "AH48" smd circle
			(at 9.549892 -14.940026 180)
			(size 0.450088 0.450088)
			(layers "F.Cu" "F.Mask" "F.Paste")
			(net "GND")
		)
		(pad "AH49" smd circle
			(at 10.489946 -14.940026 180)
			(size 0.450088 0.450088)
			(layers "F.Cu" "F.Mask" "F.Paste")
			(net "GND")
		)
		(pad "AH50" smd circle
			(at 11.43 -14.940026 180)
			(size 0.450088 0.450088)
			(layers "F.Cu" "F.Mask" "F.Paste")
			(net "GND")
		)
		(pad "AH51" smd circle
			(at 12.370054 -14.940026 180)
			(size 0.450088 0.450088)
			(layers "F.Cu" "F.Mask" "F.Paste")
			(net "GND")
		)
		(pad "AH52" smd circle
			(at 13.310108 -14.940026 180)
			(size 0.450088 0.450088)
			(layers "F.Cu" "F.Mask" "F.Paste")
			(net "GND")
		)
		(pad "AH53" smd circle
			(at 14.249908 -14.940026 180)
			(size 0.450088 0.450088)
			(layers "F.Cu" "F.Mask" "F.Paste")
			(net "GND")
		)
		(pad "AH54" smd circle
			(at 15.189962 -14.940026 180)
			(size 0.450088 0.450088)
			(layers "F.Cu" "F.Mask" "F.Paste")
			(net "PVDDIO_P0")
		)
		(pad "AH55" smd circle
			(at 16.130016 -14.940026 180)
			(size 0.450088 0.450088)
			(layers "F.Cu" "F.Mask" "F.Paste")
			(net "M_C_CPU0_SA_DQ<29>")
		)
		(pad "AH56" smd circle
			(at 17.07007 -14.940026 180)
			(size 0.450088 0.450088)
			(layers "F.Cu" "F.Mask" "F.Paste")
			(net "M_C_CPU0_SA_DQ<30>")
		)
		(pad "AH57" smd circle
			(at 18.010124 -14.940026 180)
			(size 0.450088 0.450088)
			(layers "F.Cu" "F.Mask" "F.Paste")
			(net "GND")
		)
		(pad "AH58" smd circle
			(at 18.949924 -14.940026 180)
			(size 0.450088 0.450088)
			(layers "F.Cu" "F.Mask" "F.Paste")
			(net "M_D_CPU0_SA_DQ<29>")
		)
		(pad "AH59" smd circle
			(at 19.889978 -14.940026 180)
			(size 0.450088 0.450088)
			(layers "F.Cu" "F.Mask" "F.Paste")
			(net "GND")
		)
		(pad "AH60" smd circle
			(at 20.830032 -14.940026 180)
			(size 0.450088 0.450088)
			(layers "F.Cu" "F.Mask" "F.Paste")
			(net "M_D_CPU0_SA_DQ<30>")
		)
		(pad "AH61" smd circle
			(at 21.770086 -14.940026 180)
			(size 0.450088 0.450088)
			(layers "F.Cu" "F.Mask" "F.Paste")
			(net "GND")
		)
		(pad "AH62" smd circle
			(at 22.709886 -14.940026 180)
			(size 0.450088 0.450088)
			(layers "F.Cu" "F.Mask" "F.Paste")
			(net "M_B_CPU0_SA_DQ<29>")
		)
		(pad "AH63" smd circle
			(at 23.64994 -14.940026 180)
			(size 0.450088 0.450088)
			(layers "F.Cu" "F.Mask" "F.Paste")
			(net "M_B_CPU0_SA_DQ<30>")
		)
		(pad "AH64" smd circle
			(at 24.589994 -14.940026 180)
			(size 0.450088 0.450088)
			(layers "F.Cu" "F.Mask" "F.Paste")
			(net "GND")
		)
		(pad "AH65" smd circle
			(at 25.530048 -14.940026 180)
			(size 0.450088 0.450088)
			(layers "F.Cu" "F.Mask" "F.Paste")
			(net "M_F_CPU0_SA_DQ<29>")
		)
		(pad "AH66" smd circle
			(at 26.470102 -14.940026 180)
			(size 0.450088 0.450088)
			(layers "F.Cu" "F.Mask" "F.Paste")
			(net "GND")
		)
		(pad "AH67" smd circle
			(at 27.409902 -14.940026 180)
			(size 0.450088 0.450088)
			(layers "F.Cu" "F.Mask" "F.Paste")
			(net "M_F_CPU0_SA_DQ<30>")
		)
		(pad "AH68" smd circle
			(at 28.349956 -14.940026 180)
			(size 0.450088 0.450088)
			(layers "F.Cu" "F.Mask" "F.Paste")
			(net "GND")
		)
		(pad "AH69" smd circle
			(at 29.29001 -14.940026 180)
			(size 0.450088 0.450088)
			(layers "F.Cu" "F.Mask" "F.Paste")
			(net "M_E_CPU0_SA_DQ<29>")
		)
		(pad "AH70" smd circle
			(at 30.230064 -14.940026 180)
			(size 0.450088 0.450088)
			(layers "F.Cu" "F.Mask" "F.Paste")
			(net "M_E_CPU0_SA_DQ<30>")
		)
		(pad "AH71" smd circle
			(at 31.170118 -14.940026 180)
			(size 0.450088 0.450088)
			(layers "F.Cu" "F.Mask" "F.Paste")
			(net "GND")
		)
		(pad "AH72" smd circle
			(at 32.109918 -14.940026 180)
			(size 0.450088 0.450088)
			(layers "F.Cu" "F.Mask" "F.Paste")
			(net "M_A_CPU0_SA_DQ<29>")
		)
		(pad "AH73" smd circle
			(at 33.049972 -14.940026 180)
			(size 0.450088 0.450088)
			(layers "F.Cu" "F.Mask" "F.Paste")
			(net "GND")
		)
		(pad "AH74" smd circle
			(at 33.990026 -14.940026 180)
			(size 0.450088 0.450088)
			(layers "F.Cu" "F.Mask" "F.Paste")
			(net "M_A_CPU0_SA_DQ<30>")
		)
		(pad "AJ1" smd circle
			(at -34.159952 -14.13002 180)
			(size 0.450088 0.450088)
			(layers "F.Cu" "F.Mask" "F.Paste")
			(net "GND")
		)
		(pad "AJ2" smd circle
			(at -33.219898 -14.13002 180)
			(size 0.450088 0.450088)
			(layers "F.Cu" "F.Mask" "F.Paste")
			(net "M_G_CPU0_SA_CB<0>")
		)
		(pad "AJ3" smd circle
			(at -32.280098 -14.13002 180)
			(size 0.450088 0.450088)
			(layers "F.Cu" "F.Mask" "F.Paste")
			(net "M_G_CPU0_SA_DQ<31>")
		)
		(pad "AJ4" smd circle
			(at -31.340044 -14.13002 180)
			(size 0.450088 0.450088)
			(layers "F.Cu" "F.Mask" "F.Paste")
			(net "PVDDCR_SOC_P0")
		)
		(pad "AJ5" smd circle
			(at -30.39999 -14.13002 180)
			(size 0.450088 0.450088)
			(layers "F.Cu" "F.Mask" "F.Paste")
			(net "M_K_CPU0_SA_CB<0>")
		)
		(pad "AJ6" smd circle
			(at -29.459936 -14.13002 180)
			(size 0.450088 0.450088)
			(layers "F.Cu" "F.Mask" "F.Paste")
			(net "GND")
		)
		(pad "AJ7" smd circle
			(at -28.519882 -14.13002 180)
			(size 0.450088 0.450088)
			(layers "F.Cu" "F.Mask" "F.Paste")
			(net "M_K_CPU0_SA_DQ<31>")
		)
		(pad "AJ8" smd circle
			(at -27.580082 -14.13002 180)
			(size 0.450088 0.450088)
			(layers "F.Cu" "F.Mask" "F.Paste")
			(net "GND")
		)
		(pad "AJ9" smd circle
			(at -26.640028 -14.13002 180)
			(size 0.450088 0.450088)
			(layers "F.Cu" "F.Mask" "F.Paste")
			(net "M_L_CPU0_SA_CB<0>")
		)
		(pad "AJ10" smd circle
			(at -25.699974 -14.13002 180)
			(size 0.450088 0.450088)
			(layers "F.Cu" "F.Mask" "F.Paste")
			(net "M_L_CPU0_SA_DQ<31>")
		)
		(pad "AJ11" smd circle
			(at -24.75992 -14.13002 180)
			(size 0.450088 0.450088)
			(layers "F.Cu" "F.Mask" "F.Paste")
			(net "PVDDCR_SOC_P0")
		)
		(pad "AJ12" smd circle
			(at -23.82012 -14.13002 180)
			(size 0.450088 0.450088)
			(layers "F.Cu" "F.Mask" "F.Paste")
			(net "M_H_CPU0_SA_CB<0>")
		)
		(pad "AJ13" smd circle
			(at -22.880066 -14.13002 180)
			(size 0.450088 0.450088)
			(layers "F.Cu" "F.Mask" "F.Paste")
			(net "GND")
		)
	)
)
